(kicad_pcb
	(version 20260206)
	(generator "pcbnew")
	(generator_version "10.0")
	(general
		(thickness 1.6)
		(legacy_teardrops no)
	)
	(paper "A4")
	(title_block
		(title "01162023_DA0F0TEBIF0_F0T_Expander_BD_F_brd_V02_OCP.brd")
		(comment 1 "Grand Teton / footprints 1698-1702 of 9728")
	)
	(layers
		(0 "F.Cu" signal "TOP")
		(4 "In1.Cu" signal "GND")
		(6 "In2.Cu" signal "VCC")
		(8 "In3.Cu" signal "VCC1")
		(10 "In4.Cu" signal "GND1")
		(12 "In5.Cu" signal "IN1")
		(14 "In6.Cu" signal "GND2")
		(16 "In7.Cu" signal "IN2")
		(18 "In8.Cu" signal "GND3")
		(20 "In9.Cu" signal "IN3")
		(22 "In10.Cu" signal "GND4")
		(24 "In11.Cu" signal "IN4")
		(26 "In12.Cu" signal "GND5")
		(28 "In13.Cu" signal "IN5")
		(30 "In14.Cu" signal "GND6")
		(32 "In15.Cu" signal "IN6")
		(34 "In16.Cu" signal "GND7")
		(2 "B.Cu" signal "BOTTOM")
		(9 "F.Adhes" user "F.Adhesive")
		(11 "B.Adhes" user "B.Adhesive")
		(13 "F.Paste" user "Package Geometry/Pastemask Top")
		(15 "B.Paste" user "Package Geometry/Pastemask Bottom")
		(5 "F.SilkS" user "Ref Des/Silkscreen Top")
		(7 "B.SilkS" user "Ref Des/Silkscreen Bottom")
		(1 "F.Mask" user "Board Geometry/Soldermask Top")
		(3 "B.Mask" user "Board Geometry/Soldermask Bottom")
		(17 "Dwgs.User" user "User.Drawings")
		(19 "Cmts.User" user "User.Comments")
		(21 "Eco1.User" user "User.Eco1")
		(23 "Eco2.User" user "User.Eco2")
		(25 "Edge.Cuts" user "Board Geometry/Outline")
		(27 "Margin" user)
		(31 "F.CrtYd" user "Package Geometry/Place Bound Top")
		(29 "B.CrtYd" user "Package Geometry/Place Bound Bottom")
		(35 "F.Fab" user "Ref Des/Assembly Top")
		(33 "B.Fab" user "Ref Des/Assembly Bottom")
	)
	(footprint ""
		(layer "F.Cu")
		(at 131.30149 -55.78475 -90)
		(property "Reference" "PD23"
			(at 3.96875 2.11582 90)
			(unlocked yes)
			(layer "F.SilkS")
			(effects
				(font
					(size 0.7874 0.5842)
					(thickness 0.1524)
				)
				(justify left)
			)
		)
		(property "Value" ""
			(at 0 0 270)
			(layer "F.Fab")
			(effects
				(font
					(size 1.27 1.27)
				)
			)
		)
		(duplicate_pad_numbers_are_jumpers no)
		(fp_line
			(start -3.400044 1.459992)
			(end -3.400044 -1.459992)
			(stroke
				(width 0.1524)
				(type default)
			)
			(layer "F.SilkS")
		)
		(fp_line
			(start 4.107942 1.459992)
			(end -3.400044 1.459992)
			(stroke
				(width 0.1524)
				(type default)
			)
			(layer "F.SilkS")
		)
		(fp_line
			(start -3.400044 -1.459992)
			(end 4.107942 -1.459992)
			(stroke
				(width 0.1524)
				(type default)
			)
			(layer "F.SilkS")
		)
		(fp_line
			(start 4.107942 -1.459992)
			(end 4.107942 1.459992)
			(stroke
				(width 0.1524)
				(type default)
			)
			(layer "F.SilkS")
		)
		(fp_poly
			(pts
				(xy 4.107942 -1.459992) (xy 4.107942 1.459992) (xy 3.308096 1.459992) (xy 3.308096 -1.459992)
			)
			(stroke
				(width 0)
				(type default)
			)
			(fill yes)
			(layer "F.SilkS")
		)
		(fp_line
			(start -2.29997 1.459992)
			(end -2.29997 -1.459992)
			(stroke
				(width 0.1)
				(type default)
			)
			(layer "F.Fab")
		)
		(fp_line
			(start 2.29997 1.459992)
			(end -2.29997 1.459992)
			(stroke
				(width 0.1)
				(type default)
			)
			(layer "F.Fab")
		)
		(fp_line
			(start -2.29997 -1.459992)
			(end 2.29997 -1.459992)
			(stroke
				(width 0.1)
				(type default)
			)
			(layer "F.Fab")
		)
		(fp_line
			(start 2.29997 -1.459992)
			(end 2.29997 1.459992)
			(stroke
				(width 0.1)
				(type default)
			)
			(layer "F.Fab")
		)
		(fp_text user "-"
			(at 5.4102 0.29845 90)
			(unlocked yes)
			(layer "F.SilkS")
			(effects
				(font
					(size 1.905 1.4224)
					(thickness 0.1524)
				)
				(justify left)
			)
		)
		(fp_text user "+"
			(at -4.7752 -0.12065 270)
			(unlocked yes)
			(layer "F.SilkS")
			(effects
				(font
					(size 1.905 1.4224)
					(thickness 0.1524)
				)
				(justify left)
			)
		)
		(fp_text user "-"
			(at 5.4102 0.29845 90)
			(unlocked yes)
			(layer "F.Fab")
			(effects
				(font
					(size 1.905 1.4224)
					(thickness 0.1524)
				)
				(justify left)
			)
		)
		(fp_text user "+"
			(at -4.7752 -0.12065 270)
			(unlocked yes)
			(layer "F.Fab")
			(effects
				(font
					(size 1.905 1.4224)
					(thickness 0.1524)
				)
				(justify left)
			)
		)
		(pad "A" smd rect
			(at -1.999996 0)
			(size 1.7018 2.5146)
			(layers "F.Cu" "F.Mask" "F.Paste")
			(net "GND")
		)
		(pad "C" smd rect
			(at 1.999996 0)
			(size 1.7018 2.5146)
			(layers "F.Cu" "F.Mask" "F.Paste")
			(net "P12V_SSD4_R")
		)
	)
	(footprint ""
		(layer "F.Cu")
		(at 162.67557 -69.47916 180)
		(property "Reference" "PU108"
			(at -1.9685 4.13004 90)
			(unlocked yes)
			(layer "F.SilkS")
			(effects
				(font
					(size 0.7874 0.5842)
					(thickness 0.1524)
				)
			)
		)
		(property "Value" ""
			(at 0 0 180)
			(layer "F.Fab")
			(effects
				(font
					(size 1.27 1.27)
				)
			)
		)
		(duplicate_pad_numbers_are_jumpers no)
		(fp_line
			(start 1.239774 1.495298)
			(end -1.239774 1.495298)
			(stroke
				(width 0.1524)
				(type default)
			)
			(layer "F.SilkS")
		)
		(fp_line
			(start 1.239774 -1.495298)
			(end 1.239774 1.495298)
			(stroke
				(width 0.1524)
				(type default)
			)
			(layer "F.SilkS")
		)
		(fp_line
			(start -1.239774 1.495298)
			(end -1.239774 -1.495298)
			(stroke
				(width 0.1524)
				(type default)
			)
			(layer "F.SilkS")
		)
		(fp_line
			(start -1.239774 -1.495298)
			(end 1.239774 -1.495298)
			(stroke
				(width 0.1524)
				(type default)
			)
			(layer "F.SilkS")
		)
		(fp_poly
			(pts
				(xy -1.7399 -1.288542) (xy -2.458212 -0.57023) (xy -1.38049 -0.21082)
			)
			(stroke
				(width 0)
				(type default)
			)
			(fill yes)
			(layer "F.SilkS")
		)
		(fp_line
			(start 0.8001 1.050036)
			(end -0.8001 1.050036)
			(stroke
				(width 0.1)
				(type default)
			)
			(layer "F.Fab")
		)
		(fp_line
			(start 0.8001 -1.050036)
			(end 0.8001 1.050036)
			(stroke
				(width 0.1)
				(type default)
			)
			(layer "F.Fab")
		)
		(fp_line
			(start -0.8001 1.050036)
			(end -0.8001 -1.050036)
			(stroke
				(width 0.1)
				(type default)
			)
			(layer "F.Fab")
		)
		(fp_line
			(start -0.8001 -1.050036)
			(end 0.8001 -1.050036)
			(stroke
				(width 0.1)
				(type default)
			)
			(layer "F.Fab")
		)
		(fp_poly
			(pts
				(xy -2.458974 -0.508) (xy -2.458974 0.508) (xy -1.442974 0)
			)
			(stroke
				(width 0)
				(type default)
			)
			(fill yes)
			(layer "F.Fab")
		)
		(pad "1_2" smd circle
			(at -0.374904 0 270)
			(size 0 0)
			(layers "F.Cu" "F.Mask" "F.Paste")
			(net "P12V_AUX")
		)
		(pad "3" smd rect
			(at -0.499872 0.999998 180)
			(size 0.254 0.7112)
			(layers "F.Cu" "F.Mask" "F.Paste")
			(net "GND")
		)
		(pad "4" smd rect
			(at 0 0.999998 180)
			(size 0.254 0.7112)
			(layers "F.Cu" "F.Mask" "F.Paste")
			(net "P12V_SSD5_CO_ILIMIT")
		)
		(pad "5" smd rect
			(at 0.499872 0.999998 180)
			(size 0.254 0.7112)
			(layers "F.Cu" "F.Mask" "F.Paste")
			(net "P12V_SSD5_CO_MODE")
		)
		(pad "6_7" smd circle
			(at 0.374904 0 90)
			(size 0 0)
			(layers "F.Cu" "F.Mask" "F.Paste")
			(net "P12V_SSD5_R")
		)
		(pad "8" smd rect
			(at 0.499872 -0.999998 180)
			(size 0.254 0.7112)
			(layers "F.Cu" "F.Mask" "F.Paste")
			(net "P12V_SSD5_CO_GATE")
		)
		(pad "9" smd rect
			(at 0 -0.999998 180)
			(size 0.254 0.7112)
			(layers "F.Cu" "F.Mask" "F.Paste")
			(net "P12V_SSD5_CO_EN")
		)
		(pad "10" smd rect
			(at -0.499872 -0.999998 180)
			(size 0.254 0.7112)
			(layers "F.Cu" "F.Mask" "F.Paste")
			(net "P12V_SSD5_CO_DV_DT")
		)
	)
	(footprint ""
		(layer "F.Cu")
		(at 296.957242 -453.647556)
		(property "Reference" "X69"
			(at -0.1778 -1.92913 0)
			(unlocked yes)
			(layer "F.SilkS")
			(effects
				(font
					(size 0.7874 0.5842)
					(thickness 0.1524)
				)
				(justify left)
			)
		)
		(property "Value" ""
			(at 0 0 0)
			(layer "F.Fab")
			(effects
				(font
					(size 1.27 1.27)
				)
			)
		)
		(property "Device Type" "TP_TDR_4P_FTS_MPKT4_H025P0200_IO_TP15_TP_TDR_4P_DIP"
			(at 1.30175 1.27 90)
			(unlocked yes)
			(layer "F.Fab")
			(hide yes)
			(effects
				(font
					(size 0.635 0.4064)
					(thickness 0.1524)
				)
			)
		)
		(property "User Part Number" "TP15"
			(at 1.30175 1.27 90)
			(unlocked yes)
			(layer "Cmts.User")
			(hide yes)
			(effects
				(font
					(size 0.635 0.4064)
					(thickness 0.1524)
				)
			)
		)
		(duplicate_pad_numbers_are_jumpers no)
		(fp_line
			(start 0 -1.27)
			(end 0 -0.635)
			(stroke
				(width 0.1524)
				(type default)
			)
			(layer "F.SilkS")
		)
		(fp_line
			(start 0 0.635)
			(end 0 1.905)
			(stroke
				(width 0.1524)
				(type default)
			)
			(layer "F.SilkS")
		)
		(fp_line
			(start 0 3.175)
			(end 0 3.81)
			(stroke
				(width 0.1524)
				(type default)
			)
			(layer "F.SilkS")
		)
		(fp_line
			(start 0 3.81)
			(end 2.54 3.81)
			(stroke
				(width 0.1524)
				(type default)
			)
			(layer "F.SilkS")
		)
		(fp_line
			(start 2.54 -1.27)
			(end 0 -1.27)
			(stroke
				(width 0.1524)
				(type default)
			)
			(layer "F.SilkS")
		)
		(fp_line
			(start 2.54 -1.1303)
			(end 2.54 -1.27)
			(stroke
				(width 0.1524)
				(type default)
			)
			(layer "F.SilkS")
		)
		(fp_line
			(start 2.54 1.4097)
			(end 2.54 1.1303)
			(stroke
				(width 0.1524)
				(type default)
			)
			(layer "F.SilkS")
		)
		(fp_line
			(start 2.54 3.81)
			(end 2.54 3.6703)
			(stroke
				(width 0.1524)
				(type default)
			)
			(layer "F.SilkS")
		)
		(fp_poly
			(pts
				(xy -0.761746 0) (xy -2.285746 -0.762) (xy -2.285746 0.762)
			)
			(stroke
				(width 0)
				(type default)
			)
			(fill yes)
			(layer "F.SilkS")
		)
		(fp_line
			(start 0 -1.27)
			(end 0 3.81)
			(stroke
				(width 0.1)
				(type default)
			)
			(layer "F.Fab")
		)
		(fp_line
			(start 0 3.81)
			(end 2.54 3.81)
			(stroke
				(width 0.1)
				(type default)
			)
			(layer "F.Fab")
		)
		(fp_line
			(start 2.54 -1.27)
			(end 0 -1.27)
			(stroke
				(width 0.1)
				(type default)
			)
			(layer "F.Fab")
		)
		(fp_line
			(start 2.54 3.81)
			(end 2.54 -1.27)
			(stroke
				(width 0.1)
				(type default)
			)
			(layer "F.Fab")
		)
		(fp_poly
			(pts
				(xy -0.761746 0) (xy -2.285746 -0.762) (xy -2.285746 0.762)
			)
			(stroke
				(width 0)
				(type default)
			)
			(fill yes)
			(layer "F.Fab")
		)
		(pad "1" thru_hole circle
			(at 0 0)
			(size 1.0033 1.0033)
			(drill 0.249936)
			(layers "*.Cu" "*.Mask")
			(remove_unused_layers no)
			(net "TDR_DIFF_100_IN1_DIN")
			(clearance 0.10795)
			(thermal_gap 0.10795)
			(padstack
				(mode front_inner_back)
				(layer "Inner"
					(shape circle)
					(size 0.8001 0.8001)
					(clearance 0.1524)
				)
				(layer "B.Cu"
					(shape circle)
					(size 1.0033 1.0033)
					(clearance 0.10795)
				)
			)
		)
		(pad "2" thru_hole circle
			(at 2.54 0)
			(size 1.9939 1.9939)
			(drill 0.249936)
			(layers "*.Cu" "*.Mask")
			(remove_unused_layers no)
			(net "COUPON_GND1")
			(clearance 0.10795)
			(thermal_gap 0.10795)
			(padstack
				(mode front_inner_back)
				(layer "Inner"
					(shape circle)
					(size 0.8001 0.8001)
					(clearance 0.1524)
				)
				(layer "B.Cu"
					(shape circle)
					(size 1.9939 1.9939)
					(clearance 0.10795)
				)
			)
		)
		(pad "3" thru_hole circle
			(at 2.54 2.54)
			(size 1.9939 1.9939)
			(drill 0.249936)
			(layers "*.Cu" "*.Mask")
			(remove_unused_layers no)
			(net "COUPON_GND1")
			(clearance 0.10795)
			(thermal_gap 0.10795)
			(padstack
				(mode front_inner_back)
				(layer "Inner"
					(shape circle)
					(size 0.8001 0.8001)
					(clearance 0.1524)
				)
				(layer "B.Cu"
					(shape circle)
					(size 1.9939 1.9939)
					(clearance 0.10795)
				)
			)
		)
		(pad "4" thru_hole circle
			(at 0 2.54)
			(size 1.0033 1.0033)
			(drill 0.249936)
			(layers "*.Cu" "*.Mask")
			(remove_unused_layers no)
			(net "TDR_DIFF_100_IN1_DIP")
			(clearance 0.10795)
			(thermal_gap 0.10795)
			(padstack
				(mode front_inner_back)
				(layer "Inner"
					(shape circle)
					(size 0.8001 0.8001)
					(clearance 0.1524)
				)
				(layer "B.Cu"
					(shape circle)
					(size 1.0033 1.0033)
					(clearance 0.10795)
				)
			)
		)
	)
	(footprint ""
		(layer "F.Cu")
		(at 38.599872 -151.279352 180)
		(property "Reference" "R16"
			(at 0 0 180)
			(layer "F.SilkS")
			(hide yes)
			(effects
				(font
					(size 1.27 1.27)
				)
			)
		)
		(property "Value" ""
			(at 0 0 180)
			(layer "F.Fab")
			(effects
				(font
					(size 1.27 1.27)
				)
			)
		)
		(duplicate_pad_numbers_are_jumpers no)
		(fp_line
			(start 0.7874 0.4064)
			(end -0.7874 0.4064)
			(stroke
				(width 0.1524)
				(type default)
			)
			(layer "F.SilkS")
		)
		(fp_line
			(start 0.7874 -0.4064)
			(end 0.7874 0.4064)
			(stroke
				(width 0.1524)
				(type default)
			)
			(layer "F.SilkS")
		)
		(fp_line
			(start -0.7874 0.4064)
			(end -0.7874 -0.4064)
			(stroke
				(width 0.1524)
				(type default)
			)
			(layer "F.SilkS")
		)
		(fp_line
			(start -0.7874 -0.4064)
			(end 0.7874 -0.4064)
			(stroke
				(width 0.1524)
				(type default)
			)
			(layer "F.SilkS")
		)
		(fp_line
			(start 0.67945 0.3048)
			(end 0.120396 0.3048)
			(stroke
				(width 0.1)
				(type default)
			)
			(layer "F.Fab")
		)
		(fp_line
			(start 0.67945 -0.3048)
			(end 0.67945 0.3048)
			(stroke
				(width 0.1)
				(type default)
			)
			(layer "F.Fab")
		)
		(fp_line
			(start 0.12065 -0.2794)
			(end 0.12065 -0.3048)
			(stroke
				(width 0.1)
				(type default)
			)
			(layer "F.Fab")
		)
		(fp_line
			(start 0.12065 -0.3048)
			(end 0.67945 -0.3048)
			(stroke
				(width 0.1)
				(type default)
			)
			(layer "F.Fab")
		)
		(fp_line
			(start 0.120396 0.3048)
			(end 0.120396 0.2794)
			(stroke
				(width 0.1)
				(type default)
			)
			(layer "F.Fab")
		)
		(fp_line
			(start 0.120396 0.2794)
			(end -0.12065 0.2794)
			(stroke
				(width 0.1)
				(type default)
			)
			(layer "F.Fab")
		)
		(fp_line
			(start -0.12065 0.3048)
			(end -0.67945 0.3048)
			(stroke
				(width 0.1)
				(type default)
			)
			(layer "F.Fab")
		)
		(fp_line
			(start -0.12065 0.2794)
			(end -0.12065 0.3048)
			(stroke
				(width 0.1)
				(type default)
			)
			(layer "F.Fab")
		)
		(fp_line
			(start -0.12065 -0.2794)
			(end 0.12065 -0.2794)
			(stroke
				(width 0.1)
				(type default)
			)
			(layer "F.Fab")
		)
		(fp_line
			(start -0.12065 -0.305054)
			(end -0.12065 -0.2794)
			(stroke
				(width 0.1)
				(type default)
			)
			(layer "F.Fab")
		)
		(fp_line
			(start -0.67945 0.3048)
			(end -0.67945 -0.305054)
			(stroke
				(width 0.1)
				(type default)
			)
			(layer "F.Fab")
		)
		(fp_line
			(start -0.67945 -0.305054)
			(end -0.12065 -0.305054)
			(stroke
				(width 0.1)
				(type default)
			)
			(layer "F.Fab")
		)
		(pad "1" smd circle
			(at -0.40005 0 180)
			(size 0 0)
			(layers "F.Cu" "F.Mask" "F.Paste")
			(net "NCSI_NIC0_RXD0")
		)
		(pad "2" smd circle
			(at 0.40005 0 180)
			(size 0 0)
			(layers "F.Cu" "F.Mask" "F.Paste")
			(net "GND")
		)
	)
	(footprint ""
		(layer "F.Cu")
		(at 102.521512 -87.487506 180)
		(property "Reference" "C2670"
			(at 0 0 180)
			(layer "F.SilkS")
			(hide yes)
			(effects
				(font
					(size 1.27 1.27)
				)
			)
		)
		(property "Value" ""
			(at 0 0 180)
			(layer "F.Fab")
			(effects
				(font
					(size 1.27 1.27)
				)
			)
		)
		(duplicate_pad_numbers_are_jumpers no)
		(fp_line
			(start 1.2954 0.5842)
			(end -1.2954 0.5842)
			(stroke
				(width 0.1524)
				(type default)
			)
			(layer "F.SilkS")
		)
		(fp_line
			(start 1.2954 -0.5842)
			(end 1.2954 0.5842)
			(stroke
				(width 0.1524)
				(type default)
			)
			(layer "F.SilkS")
		)
		(fp_line
			(start -1.2954 0.5842)
			(end -1.2954 -0.5842)
			(stroke
				(width 0.1524)
				(type default)
			)
			(layer "F.SilkS")
		)
		(fp_line
			(start -1.2954 -0.5842)
			(end 1.2954 -0.5842)
			(stroke
				(width 0.1524)
				(type default)
			)
			(layer "F.SilkS")
		)
		(fp_line
			(start 1.1938 0.4064)
			(end 0.8636 0.4064)
			(stroke
				(width 0.1)
				(type default)
			)
			(layer "F.Fab")
		)
		(fp_line
			(start 1.1938 -0.4064)
			(end 1.1938 0.4064)
			(stroke
				(width 0.1)
				(type default)
			)
			(layer "F.Fab")
		)
		(fp_line
			(start 0.8636 0.4572)
			(end -0.8636 0.4572)
			(stroke
				(width 0.1)
				(type default)
			)
			(layer "F.Fab")
		)
		(fp_line
			(start 0.8636 0.4064)
			(end 0.8636 0.4572)
			(stroke
				(width 0.1)
				(type default)
			)
			(layer "F.Fab")
		)
		(fp_line
			(start 0.8636 -0.4064)
			(end 1.1938 -0.4064)
			(stroke
				(width 0.1)
				(type default)
			)
			(layer "F.Fab")
		)
		(fp_line
			(start 0.8636 -0.4572)
			(end 0.8636 -0.4064)
			(stroke
				(width 0.1)
				(type default)
			)
			(layer "F.Fab")
		)
		(fp_line
			(start -0.8636 0.4572)
			(end -0.8636 0.4064)
			(stroke
				(width 0.1)
				(type default)
			)
			(layer "F.Fab")
		)
		(fp_line
			(start -0.8636 0.4064)
			(end -1.1938 0.4064)
			(stroke
				(width 0.1)
				(type default)
			)
			(layer "F.Fab")
		)
		(fp_line
			(start -0.8636 -0.4064)
			(end -0.8636 -0.4572)
			(stroke
				(width 0.1)
				(type default)
			)
			(layer "F.Fab")
		)
		(fp_line
			(start -0.8636 -0.4572)
			(end 0.8636 -0.4572)
			(stroke
				(width 0.1)
				(type default)
			)
			(layer "F.Fab")
		)
		(fp_line
			(start -1.1938 0.4064)
			(end -1.1938 -0.4064)
			(stroke
				(width 0.1)
				(type default)
			)
			(layer "F.Fab")
		)
		(fp_line
			(start -1.1938 -0.4064)
			(end -0.8636 -0.4064)
			(stroke
				(width 0.1)
				(type default)
			)
			(layer "F.Fab")
		)
		(pad "1" smd rect
			(at -0.7366 0 90)
			(size 0.7112 0.8128)
			(layers "F.Cu" "F.Mask" "F.Paste")
			(net "P3V3_VDDAR_9ZXL0851_0_7")
		)
		(pad "2" smd rect
			(at 0.7366 0 90)
			(size 0.7112 0.8128)
			(layers "F.Cu" "F.Mask" "F.Paste")
			(net "GND")
		)
	)
)
